# T6G (Grand Teton) — schematic netlist excerpt (pin names and nets, part order shuffled) for the footprints in the layout excerpt that follows; sources: Cadence DE-HDL packaged netlist, KiCad conversion of 04192023_DAF0TMB3IC0_F0TG_MB_C_brd_V02_OCP.brd

C2146  Q_CAP  22UF 4V 20% X6S  pkg C0402  page 68 : A = PVDD11_S3_P0 ; B = GND
PR3952  Q_RES  71.5K 1% EMPTY  pkg 0402LF  page 147 : A = P12V_E1S_0 ; B = P12V_E1S_OV_FB_0

(kicad_pcb
	(version 20260206)
	(generator "pcbnew")
	(generator_version "10.0")
	(general
		(thickness 1.6)
		(legacy_teardrops no)
	)
	(paper "A4")
	(title_block
		(title "04192023_DAF0TMB3IC0_F0TG_MB_C_brd_V02_OCP.brd")
		(comment 1 "Grand Teton / footprints 1763-1764 of 8354")
	)
	(layers
		(0 "F.Cu" signal "TOP")
		(4 "In1.Cu" signal "GND")
		(6 "In2.Cu" signal "IN1")
		(8 "In3.Cu" signal "GND1")
		(10 "In4.Cu" signal "IN2")
		(12 "In5.Cu" signal "GND2")
		(14 "In6.Cu" signal "IN3")
		(16 "In7.Cu" signal "GND3")
		(18 "In8.Cu" signal "VCC")
		(20 "In9.Cu" signal "VCC1")
		(22 "In10.Cu" signal "GND4")
		(24 "In11.Cu" signal "IN4")
		(26 "In12.Cu" signal "GND5")
		(28 "In13.Cu" signal "IN5")
		(30 "In14.Cu" signal "GND6")
		(32 "In15.Cu" signal "IN6")
		(34 "In16.Cu" signal "GND7")
		(2 "B.Cu" signal "BOTTOM")
		(9 "F.Adhes" user "F.Adhesive")
		(11 "B.Adhes" user "B.Adhesive")
		(13 "F.Paste" user "Package Geometry/Pastemask Top")
		(15 "B.Paste" user "Package Geometry/Pastemask Bottom")
		(5 "F.SilkS" user "Ref Des/Silkscreen Top")
		(7 "B.SilkS" user "Ref Des/Silkscreen Bottom")
		(1 "F.Mask" user "Board Geometry/Soldermask Top")
		(3 "B.Mask" user "Board Geometry/Soldermask Bottom")
		(17 "Dwgs.User" user "User.Drawings")
		(19 "Cmts.User" user "User.Comments")
		(21 "Eco1.User" user "User.Eco1")
		(23 "Eco2.User" user "User.Eco2")
		(25 "Edge.Cuts" user "Board Geometry/Outline")
		(27 "Margin" user)
		(31 "F.CrtYd" user "Package Geometry/Place Bound Top")
		(29 "B.CrtYd" user "Package Geometry/Place Bound Bottom")
		(35 "F.Fab" user "Ref Des/Assembly Top")
		(33 "B.Fab" user "Ref Des/Assembly Bottom")
	)
	(footprint ""
		(layer "F.Cu")
		(at 360.367072 -261.747762 -90)
		(property "Reference" "C2146"
			(at 0 0 270)
			(layer "F.SilkS")
			(hide yes)
			(effects
				(font
					(size 1.27 1.27)
				)
			)
		)
		(property "Value" ""
			(at 0 0 270)
			(layer "F.Fab")
			(effects
				(font
					(size 1.27 1.27)
				)
			)
		)
		(duplicate_pad_numbers_are_jumpers no)
		(fp_line
			(start -0.7874 0.4064)
			(end -0.7874 -0.4064)
			(stroke
				(width 0.1524)
				(type default)
			)
			(layer "F.SilkS")
		)
		(fp_line
			(start 0.7874 0.4064)
			(end -0.7874 0.4064)
			(stroke
				(width 0.1524)
				(type default)
			)
			(layer "F.SilkS")
		)
		(fp_line
			(start -0.7874 -0.4064)
			(end 0.7874 -0.4064)
			(stroke
				(width 0.1524)
				(type default)
			)
			(layer "F.SilkS")
		)
		(fp_line
			(start 0.7874 -0.4064)
			(end 0.7874 0.4064)
			(stroke
				(width 0.1524)
				(type default)
			)
			(layer "F.SilkS")
		)
		(fp_line
			(start -0.67945 0.3048)
			(end -0.67945 -0.305054)
			(stroke
				(width 0.1)
				(type default)
			)
			(layer "F.Fab")
		)
		(fp_line
			(start -0.12065 0.3048)
			(end -0.67945 0.3048)
			(stroke
				(width 0.1)
				(type default)
			)
			(layer "F.Fab")
		)
		(fp_line
			(start 0.120396 0.3048)
			(end 0.120396 0.2794)
			(stroke
				(width 0.1)
				(type default)
			)
			(layer "F.Fab")
		)
		(fp_line
			(start 0.67945 0.3048)
			(end 0.120396 0.3048)
			(stroke
				(width 0.1)
				(type default)
			)
			(layer "F.Fab")
		)
		(fp_line
			(start -0.12065 0.2794)
			(end -0.12065 0.3048)
			(stroke
				(width 0.1)
				(type default)
			)
			(layer "F.Fab")
		)
		(fp_line
			(start 0.120396 0.2794)
			(end -0.12065 0.2794)
			(stroke
				(width 0.1)
				(type default)
			)
			(layer "F.Fab")
		)
		(fp_line
			(start -0.12065 -0.2794)
			(end 0.12065 -0.2794)
			(stroke
				(width 0.1)
				(type default)
			)
			(layer "F.Fab")
		)
		(fp_line
			(start 0.12065 -0.2794)
			(end 0.12065 -0.3048)
			(stroke
				(width 0.1)
				(type default)
			)
			(layer "F.Fab")
		)
		(fp_line
			(start 0.12065 -0.3048)
			(end 0.67945 -0.3048)
			(stroke
				(width 0.1)
				(type default)
			)
			(layer "F.Fab")
		)
		(fp_line
			(start 0.67945 -0.3048)
			(end 0.67945 0.3048)
			(stroke
				(width 0.1)
				(type default)
			)
			(layer "F.Fab")
		)
		(fp_line
			(start -0.67945 -0.305054)
			(end -0.12065 -0.305054)
			(stroke
				(width 0.1)
				(type default)
			)
			(layer "F.Fab")
		)
		(fp_line
			(start -0.12065 -0.305054)
			(end -0.12065 -0.2794)
			(stroke
				(width 0.1)
				(type default)
			)
			(layer "F.Fab")
		)
		(pad "1" smd circle
			(at -0.40005 0 270)
			(size 0 0)
			(layers "F.Cu" "F.Mask" "F.Paste")
			(net "PVDD11_S3_P0")
		)
		(pad "2" smd circle
			(at 0.40005 0 270)
			(size 0 0)
			(layers "F.Cu" "F.Mask" "F.Paste")
			(net "GND")
		)
	)
	(footprint ""
		(layer "F.Cu")
		(at 252.961648 -57.209182)
		(property "Reference" "PR3952"
			(at 0 0 0)
			(layer "F.SilkS")
			(hide yes)
			(effects
				(font
					(size 1.27 1.27)
				)
			)
		)
		(property "Value" ""
			(at 0 0 0)
			(layer "F.Fab")
			(effects
				(font
					(size 1.27 1.27)
				)
			)
		)
		(duplicate_pad_numbers_are_jumpers no)
		(fp_line
			(start -0.7874 -0.4064)
			(end 0.7874 -0.4064)
			(stroke
				(width 0.1524)
				(type default)
			)
			(layer "F.SilkS")
		)
		(fp_line
			(start -0.7874 0.4064)
			(end -0.7874 -0.4064)
			(stroke
				(width 0.1524)
				(type default)
			)
			(layer "F.SilkS")
		)
		(fp_line
			(start 0.7874 -0.4064)
			(end 0.7874 0.4064)
			(stroke
				(width 0.1524)
				(type default)
			)
			(layer "F.SilkS")
		)
		(fp_line
			(start 0.7874 0.4064)
			(end -0.7874 0.4064)
			(stroke
				(width 0.1524)
				(type default)
			)
			(layer "F.SilkS")
		)
		(fp_line
			(start -0.67945 -0.305054)
			(end -0.12065 -0.305054)
			(stroke
				(width 0.1)
				(type default)
			)
			(layer "F.Fab")
		)
		(fp_line
			(start -0.67945 0.3048)
			(end -0.67945 -0.305054)
			(stroke
				(width 0.1)
				(type default)
			)
			(layer "F.Fab")
		)
		(fp_line
			(start -0.12065 -0.305054)
			(end -0.12065 -0.2794)
			(stroke
				(width 0.1)
				(type default)
			)
			(layer "F.Fab")
		)
		(fp_line
			(start -0.12065 -0.2794)
			(end 0.12065 -0.2794)
			(stroke
				(width 0.1)
				(type default)
			)
			(layer "F.Fab")
		)
		(fp_line
			(start -0.12065 0.2794)
			(end -0.12065 0.3048)
			(stroke
				(width 0.1)
				(type default)
			)
			(layer "F.Fab")
		)
		(fp_line
			(start -0.12065 0.3048)
			(end -0.67945 0.3048)
			(stroke
				(width 0.1)
				(type default)
			)
			(layer "F.Fab")
		)
		(fp_line
			(start 0.120396 0.2794)
			(end -0.12065 0.2794)
			(stroke
				(width 0.1)
				(type default)
			)
			(layer "F.Fab")
		)
		(fp_line
			(start 0.120396 0.3048)
			(end 0.120396 0.2794)
			(stroke
				(width 0.1)
				(type default)
			)
			(layer "F.Fab")
		)
		(fp_line
			(start 0.12065 -0.3048)
			(end 0.67945 -0.3048)
			(stroke
				(width 0.1)
				(type default)
			)
			(layer "F.Fab")
		)
		(fp_line
			(start 0.12065 -0.2794)
			(end 0.12065 -0.3048)
			(stroke
				(width 0.1)
				(type default)
			)
			(layer "F.Fab")
		)
		(fp_line
			(start 0.67945 -0.3048)
			(end 0.67945 0.3048)
			(stroke
				(width 0.1)
				(type default)
			)
			(layer "F.Fab")
		)
		(fp_line
			(start 0.67945 0.3048)
			(end 0.120396 0.3048)
			(stroke
				(width 0.1)
				(type default)
			)
			(layer "F.Fab")
		)
		(pad "1" smd circle
			(at -0.40005 0)
			(size 0 0)
			(layers "F.Cu" "F.Mask" "F.Paste")
			(net "P12V_E1S_0")
		)
		(pad "2" smd circle
			(at 0.40005 0)
			(size 0 0)
			(layers "F.Cu" "F.Mask" "F.Paste")
			(net "P12V_E1S_OV_FB_0")
		)
	)
)
